# T6G (Grand Teton) — schematic netlist excerpt (pin names and nets, part order shuffled) for the footprints in the layout excerpt that follows; sources: Cadence DE-HDL packaged netlist, KiCad conversion of 04192023_DAF0TMB3IC0_F0TG_MB_C_brd_V02_OCP.brd

PC62  Q_CAP  0.1UF 25V 10% X7R  pkg 0402  page 226 : A = PVDD18_S5_P1_REF ; B = PVDD18_SS_P1_RGND
R4483  Q_RES  49.9 1% EMPTY  pkg 0402LF  page 234 : A = USB2_HOST_BMC_B_BUF_DN ; B = GND

(kicad_pcb
	(version 20260206)
	(generator "pcbnew")
	(generator_version "10.0")
	(general
		(thickness 1.6)
		(legacy_teardrops no)
	)
	(paper "A4")
	(title_block
		(title "04192023_DAF0TMB3IC0_F0TG_MB_C_brd_V02_OCP.brd")
		(comment 1 "Grand Teton / footprints 1257-1258 of 8354")
	)
	(layers
		(0 "F.Cu" signal "TOP")
		(4 "In1.Cu" signal "GND")
		(6 "In2.Cu" signal "IN1")
		(8 "In3.Cu" signal "GND1")
		(10 "In4.Cu" signal "IN2")
		(12 "In5.Cu" signal "GND2")
		(14 "In6.Cu" signal "IN3")
		(16 "In7.Cu" signal "GND3")
		(18 "In8.Cu" signal "VCC")
		(20 "In9.Cu" signal "VCC1")
		(22 "In10.Cu" signal "GND4")
		(24 "In11.Cu" signal "IN4")
		(26 "In12.Cu" signal "GND5")
		(28 "In13.Cu" signal "IN5")
		(30 "In14.Cu" signal "GND6")
		(32 "In15.Cu" signal "IN6")
		(34 "In16.Cu" signal "GND7")
		(2 "B.Cu" signal "BOTTOM")
		(9 "F.Adhes" user "F.Adhesive")
		(11 "B.Adhes" user "B.Adhesive")
		(13 "F.Paste" user "Package Geometry/Pastemask Top")
		(15 "B.Paste" user "Package Geometry/Pastemask Bottom")
		(5 "F.SilkS" user "Ref Des/Silkscreen Top")
		(7 "B.SilkS" user "Ref Des/Silkscreen Bottom")
		(1 "F.Mask" user "Board Geometry/Soldermask Top")
		(3 "B.Mask" user "Board Geometry/Soldermask Bottom")
		(17 "Dwgs.User" user "User.Drawings")
		(19 "Cmts.User" user "User.Comments")
		(21 "Eco1.User" user "User.Eco1")
		(23 "Eco2.User" user "User.Eco2")
		(25 "Edge.Cuts" user "Board Geometry/Outline")
		(27 "Margin" user)
		(31 "F.CrtYd" user "Package Geometry/Place Bound Top")
		(29 "B.CrtYd" user "Package Geometry/Place Bound Bottom")
		(35 "F.Fab" user "Ref Des/Assembly Top")
		(33 "B.Fab" user "Ref Des/Assembly Bottom")
	)
	(footprint ""
		(layer "F.Cu")
		(at 70.713854 -148.635212)
		(property "Reference" "PC62"
			(at 0 0 0)
			(layer "F.SilkS")
			(hide yes)
			(effects
				(font
					(size 1.27 1.27)
				)
			)
		)
		(property "Value" ""
			(at 0 0 0)
			(layer "F.Fab")
			(effects
				(font
					(size 1.27 1.27)
				)
			)
		)
		(duplicate_pad_numbers_are_jumpers no)
		(fp_line
			(start -0.7874 -0.4064)
			(end 0.7874 -0.4064)
			(stroke
				(width 0.1524)
				(type default)
			)
			(layer "F.SilkS")
		)
		(fp_line
			(start -0.7874 0.4064)
			(end -0.7874 -0.4064)
			(stroke
				(width 0.1524)
				(type default)
			)
			(layer "F.SilkS")
		)
		(fp_line
			(start 0.7874 -0.4064)
			(end 0.7874 0.4064)
			(stroke
				(width 0.1524)
				(type default)
			)
			(layer "F.SilkS")
		)
		(fp_line
			(start 0.7874 0.4064)
			(end -0.7874 0.4064)
			(stroke
				(width 0.1524)
				(type default)
			)
			(layer "F.SilkS")
		)
		(fp_line
			(start -0.67945 -0.305054)
			(end -0.12065 -0.305054)
			(stroke
				(width 0.1)
				(type default)
			)
			(layer "F.Fab")
		)
		(fp_line
			(start -0.67945 0.3048)
			(end -0.67945 -0.305054)
			(stroke
				(width 0.1)
				(type default)
			)
			(layer "F.Fab")
		)
		(fp_line
			(start -0.12065 -0.305054)
			(end -0.12065 -0.2794)
			(stroke
				(width 0.1)
				(type default)
			)
			(layer "F.Fab")
		)
		(fp_line
			(start -0.12065 -0.2794)
			(end 0.12065 -0.2794)
			(stroke
				(width 0.1)
				(type default)
			)
			(layer "F.Fab")
		)
		(fp_line
			(start -0.12065 0.2794)
			(end -0.12065 0.3048)
			(stroke
				(width 0.1)
				(type default)
			)
			(layer "F.Fab")
		)
		(fp_line
			(start -0.12065 0.3048)
			(end -0.67945 0.3048)
			(stroke
				(width 0.1)
				(type default)
			)
			(layer "F.Fab")
		)
		(fp_line
			(start 0.120396 0.2794)
			(end -0.12065 0.2794)
			(stroke
				(width 0.1)
				(type default)
			)
			(layer "F.Fab")
		)
		(fp_line
			(start 0.120396 0.3048)
			(end 0.120396 0.2794)
			(stroke
				(width 0.1)
				(type default)
			)
			(layer "F.Fab")
		)
		(fp_line
			(start 0.12065 -0.3048)
			(end 0.67945 -0.3048)
			(stroke
				(width 0.1)
				(type default)
			)
			(layer "F.Fab")
		)
		(fp_line
			(start 0.12065 -0.2794)
			(end 0.12065 -0.3048)
			(stroke
				(width 0.1)
				(type default)
			)
			(layer "F.Fab")
		)
		(fp_line
			(start 0.67945 -0.3048)
			(end 0.67945 0.3048)
			(stroke
				(width 0.1)
				(type default)
			)
			(layer "F.Fab")
		)
		(fp_line
			(start 0.67945 0.3048)
			(end 0.120396 0.3048)
			(stroke
				(width 0.1)
				(type default)
			)
			(layer "F.Fab")
		)
		(pad "1" smd circle
			(at -0.40005 0)
			(size 0 0)
			(layers "F.Cu" "F.Mask" "F.Paste")
			(net "PVDD18_S5_P1_REF")
		)
		(pad "2" smd circle
			(at 0.40005 0)
			(size 0 0)
			(layers "F.Cu" "F.Mask" "F.Paste")
			(net "PVDD18_SS_P1_RGND")
		)
	)
	(footprint ""
		(layer "F.Cu")
		(at 17.045432 -107.631484)
		(property "Reference" "R4483"
			(at 0 0 0)
			(layer "F.SilkS")
			(hide yes)
			(effects
				(font
					(size 1.27 1.27)
				)
			)
		)
		(property "Value" ""
			(at 0 0 0)
			(layer "F.Fab")
			(effects
				(font
					(size 1.27 1.27)
				)
			)
		)
		(duplicate_pad_numbers_are_jumpers no)
		(fp_line
			(start -0.7874 -0.4064)
			(end 0.7874 -0.4064)
			(stroke
				(width 0.1524)
				(type default)
			)
			(layer "F.SilkS")
		)
		(fp_line
			(start -0.7874 0.4064)
			(end -0.7874 -0.4064)
			(stroke
				(width 0.1524)
				(type default)
			)
			(layer "F.SilkS")
		)
		(fp_line
			(start 0.7874 -0.4064)
			(end 0.7874 0.4064)
			(stroke
				(width 0.1524)
				(type default)
			)
			(layer "F.SilkS")
		)
		(fp_line
			(start 0.7874 0.4064)
			(end -0.7874 0.4064)
			(stroke
				(width 0.1524)
				(type default)
			)
			(layer "F.SilkS")
		)
		(fp_line
			(start -0.67945 -0.305054)
			(end -0.12065 -0.305054)
			(stroke
				(width 0.1)
				(type default)
			)
			(layer "F.Fab")
		)
		(fp_line
			(start -0.67945 0.3048)
			(end -0.67945 -0.305054)
			(stroke
				(width 0.1)
				(type default)
			)
			(layer "F.Fab")
		)
		(fp_line
			(start -0.12065 -0.305054)
			(end -0.12065 -0.2794)
			(stroke
				(width 0.1)
				(type default)
			)
			(layer "F.Fab")
		)
		(fp_line
			(start -0.12065 -0.2794)
			(end 0.12065 -0.2794)
			(stroke
				(width 0.1)
				(type default)
			)
			(layer "F.Fab")
		)
		(fp_line
			(start -0.12065 0.2794)
			(end -0.12065 0.3048)
			(stroke
				(width 0.1)
				(type default)
			)
			(layer "F.Fab")
		)
		(fp_line
			(start -0.12065 0.3048)
			(end -0.67945 0.3048)
			(stroke
				(width 0.1)
				(type default)
			)
			(layer "F.Fab")
		)
		(fp_line
			(start 0.120396 0.2794)
			(end -0.12065 0.2794)
			(stroke
				(width 0.1)
				(type default)
			)
			(layer "F.Fab")
		)
		(fp_line
			(start 0.120396 0.3048)
			(end 0.120396 0.2794)
			(stroke
				(width 0.1)
				(type default)
			)
			(layer "F.Fab")
		)
		(fp_line
			(start 0.12065 -0.3048)
			(end 0.67945 -0.3048)
			(stroke
				(width 0.1)
				(type default)
			)
			(layer "F.Fab")
		)
		(fp_line
			(start 0.12065 -0.2794)
			(end 0.12065 -0.3048)
			(stroke
				(width 0.1)
				(type default)
			)
			(layer "F.Fab")
		)
		(fp_line
			(start 0.67945 -0.3048)
			(end 0.67945 0.3048)
			(stroke
				(width 0.1)
				(type default)
			)
			(layer "F.Fab")
		)
		(fp_line
			(start 0.67945 0.3048)
			(end 0.120396 0.3048)
			(stroke
				(width 0.1)
				(type default)
			)
			(layer "F.Fab")
		)
		(pad "1" smd circle
			(at -0.40005 0)
			(size 0 0)
			(layers "F.Cu" "F.Mask" "F.Paste")
			(net "USB2_HOST_BMC_B_BUF_DN")
		)
		(pad "2" smd circle
			(at 0.40005 0)
			(size 0 0)
			(layers "F.Cu" "F.Mask" "F.Paste")
			(net "GND")
		)
	)
)
